(kicad_pcb
	(version 20260206)
	(generator "pcbnew")
	(generator_version "10.0")
	(general
		(thickness 1.6)
		(legacy_teardrops no)
	)
	(paper "A4")
	(title_block
		(title "v1-chassis-manager — T6M_CM_d_v01_1031_1645.brd")
		(comment 1 "Open CloudServer (Microsoft) / footprints 1142-1150 of 2512")
	)
	(layers
		(0 "F.Cu" signal "TOP")
		(4 "In1.Cu" signal "GND1")
		(6 "In2.Cu" signal "IN1")
		(8 "In3.Cu" signal "VCC1")
		(10 "In4.Cu" signal "VCC2")
		(12 "In5.Cu" signal "GND2")
		(14 "In6.Cu" signal "IN2")
		(16 "In7.Cu" signal "IN3")
		(18 "In8.Cu" signal "GND3")
		(2 "B.Cu" signal "BOTTOM")
		(9 "F.Adhes" user "F.Adhesive")
		(11 "B.Adhes" user "B.Adhesive")
		(13 "F.Paste" user "Package Geometry/Pastemask Top")
		(15 "B.Paste" user "Package Geometry/Pastemask Bottom")
		(5 "F.SilkS" user "Ref Des/Silkscreen Top")
		(7 "B.SilkS" user "Ref Des/Silkscreen Bottom")
		(1 "F.Mask" user "Board Geometry/Soldermask Top")
		(3 "B.Mask" user "Board Geometry/Soldermask Bottom")
		(17 "Dwgs.User" user "User.Drawings")
		(19 "Cmts.User" user "User.Comments")
		(21 "Eco1.User" user "User.Eco1")
		(23 "Eco2.User" user "User.Eco2")
		(25 "Edge.Cuts" user "Board Geometry/Outline")
		(27 "Margin" user)
		(31 "F.CrtYd" user "Package Geometry/Place Bound Top")
		(29 "B.CrtYd" user "Package Geometry/Place Bound Bottom")
		(35 "F.Fab" user "Ref Des/Assembly Top")
		(33 "B.Fab" user "Ref Des/Assembly Bottom")
	)
	(footprint ""
		(layer "F.Cu")
		(at 112.717072 -132.012944 90)
		(property "Reference" "PR55"
			(at -0.690372 5.279136 90)
			(unlocked yes)
			(layer "F.SilkS")
			(effects
				(font
					(size 0.7874 0.5842)
					(thickness 0.1524)
				)
				(justify left)
			)
		)
		(property "Value" ""
			(at 0 0 90)
			(layer "F.Fab")
			(effects
				(font
					(size 1.27 1.27)
				)
			)
		)
		(duplicate_pad_numbers_are_jumpers no)
		(fp_line
			(start 0.7874 -0.4064)
			(end 0.7874 0.4064)
			(stroke
				(width 0.1524)
				(type default)
			)
			(layer "F.SilkS")
		)
		(fp_line
			(start -0.7874 -0.4064)
			(end 0.7874 -0.4064)
			(stroke
				(width 0.1524)
				(type default)
			)
			(layer "F.SilkS")
		)
		(fp_line
			(start 0.7874 0.4064)
			(end -0.7874 0.4064)
			(stroke
				(width 0.1524)
				(type default)
			)
			(layer "F.SilkS")
		)
		(fp_line
			(start -0.7874 0.4064)
			(end -0.7874 -0.4064)
			(stroke
				(width 0.1524)
				(type default)
			)
			(layer "F.SilkS")
		)
		(fp_poly
			(pts
				(xy -0.508 0.2794) (xy -0.508 0.2286) (xy -0.635 0.2286) (xy -0.635 -0.254) (xy -0.5334 -0.254)
				(xy -0.5334 -0.2794) (xy 0.5334 -0.2794) (xy 0.5334 -0.254) (xy 0.635 -0.254) (xy 0.635 0.254) (xy 0.5334 0.254)
				(xy 0.5334 0.2794)
			)
			(stroke
				(width 0)
				(type default)
			)
			(fill no)
			(layer "F.CrtYd")
		)
		(pad "1" smd rect
			(at 0.40005 0 90)
			(size 0.4572 0.508)
			(layers "F.Cu" "F.Mask" "F.Paste")
			(net "VR_PVCCP_NODE1_ISEN1P_CC")
		)
		(pad "2" smd rect
			(at -0.40005 0 90)
			(size 0.4572 0.508)
			(layers "F.Cu" "F.Mask" "F.Paste")
			(net "ISENSE_PVCCP_NODE1_ISEN1P")
		)
	)
	(footprint ""
		(layer "F.Cu")
		(at 108.82376 -166.790624)
		(property "Reference" "U68"
			(at 87.40648 71.02729 0)
			(unlocked yes)
			(layer "F.SilkS")
			(effects
				(font
					(size 0.7874 0.5842)
					(thickness 0.1524)
				)
			)
		)
		(property "Value" ""
			(at 0 0 0)
			(layer "F.Fab")
			(effects
				(font
					(size 1.27 1.27)
				)
			)
		)
		(duplicate_pad_numbers_are_jumpers no)
		(fp_line
			(start -1.651 -2.0574)
			(end 1.651 -2.0574)
			(stroke
				(width 0.1524)
				(type default)
			)
			(layer "F.SilkS")
		)
		(fp_line
			(start -1.651 -0.381)
			(end -1.651 -2.0574)
			(stroke
				(width 0.1524)
				(type default)
			)
			(layer "F.SilkS")
		)
		(fp_line
			(start -1.651 0.381)
			(end -1.016 0)
			(stroke
				(width 0.1524)
				(type default)
			)
			(layer "F.SilkS")
		)
		(fp_line
			(start -1.651 2.0574)
			(end -1.651 0.381)
			(stroke
				(width 0.1524)
				(type default)
			)
			(layer "F.SilkS")
		)
		(fp_line
			(start -1.016 0)
			(end -1.651 -0.381)
			(stroke
				(width 0.1524)
				(type default)
			)
			(layer "F.SilkS")
		)
		(fp_line
			(start 1.651 -2.0574)
			(end 1.651 2.0574)
			(stroke
				(width 0.1524)
				(type default)
			)
			(layer "F.SilkS")
		)
		(fp_line
			(start 1.651 2.0574)
			(end -1.651 2.0574)
			(stroke
				(width 0.1524)
				(type default)
			)
			(layer "F.SilkS")
		)
		(fp_rect
			(start -1.524 1.905)
			(end 1.524 -1.905)
			(stroke
				(width 0)
				(type default)
			)
			(fill no)
			(layer "F.CrtYd")
		)
		(pad "1" smd rect
			(at -0.94996 1.225042)
			(size 0.5588 1.3462)
			(layers "F.Cu" "F.Mask" "F.Paste")
			(net "FNACTRL1_TMP_IN")
		)
		(pad "2" smd rect
			(at 0 1.225042)
			(size 0.5588 1.3462)
			(layers "F.Cu" "F.Mask" "F.Paste")
			(net "CPLD_FAN_MAX_CTRL")
		)
		(pad "3" smd rect
			(at 0.94996 1.225042)
			(size 0.5588 1.3462)
			(layers "F.Cu" "F.Mask" "F.Paste")
			(net "TMP05_FUNC1")
		)
		(pad "4" smd rect
			(at 0.94996 -1.225042)
			(size 0.5588 1.3462)
			(layers "F.Cu" "F.Mask" "F.Paste")
			(net "GND")
		)
		(pad "5" smd rect
			(at -0.94996 -1.225042)
			(size 0.5588 1.3462)
			(layers "F.Cu" "F.Mask" "F.Paste")
			(net "P3V3_NODE1")
		)
	)
	(footprint ""
		(layer "F.Cu")
		(at 61.96076 -188.126624 -90)
		(property "Reference" "R937"
			(at -4.548886 -0.107442 90)
			(unlocked yes)
			(layer "F.SilkS")
			(effects
				(font
					(size 0.7874 0.5842)
					(thickness 0.1524)
				)
				(justify left)
			)
		)
		(property "Value" ""
			(at 0 0 270)
			(layer "F.Fab")
			(effects
				(font
					(size 1.27 1.27)
				)
			)
		)
		(duplicate_pad_numbers_are_jumpers no)
		(fp_line
			(start -0.7874 0.4064)
			(end -0.7874 -0.4064)
			(stroke
				(width 0.1524)
				(type default)
			)
			(layer "F.SilkS")
		)
		(fp_line
			(start 0.7874 0.4064)
			(end -0.7874 0.4064)
			(stroke
				(width 0.1524)
				(type default)
			)
			(layer "F.SilkS")
		)
		(fp_line
			(start -0.7874 -0.4064)
			(end 0.7874 -0.4064)
			(stroke
				(width 0.1524)
				(type default)
			)
			(layer "F.SilkS")
		)
		(fp_line
			(start 0.7874 -0.4064)
			(end 0.7874 0.4064)
			(stroke
				(width 0.1524)
				(type default)
			)
			(layer "F.SilkS")
		)
		(fp_poly
			(pts
				(xy -0.508 0.2794) (xy -0.508 0.2286) (xy -0.635 0.2286) (xy -0.635 -0.254) (xy -0.5334 -0.254)
				(xy -0.5334 -0.2794) (xy 0.5334 -0.2794) (xy 0.5334 -0.254) (xy 0.635 -0.254) (xy 0.635 0.254) (xy 0.5334 0.254)
				(xy 0.5334 0.2794)
			)
			(stroke
				(width 0)
				(type default)
			)
			(fill no)
			(layer "F.CrtYd")
		)
		(pad "1" smd rect
			(at 0.40005 0 270)
			(size 0.4572 0.508)
			(layers "F.Cu" "F.Mask" "F.Paste")
			(net "UART_T2_NODE2_RXD")
		)
		(pad "2" smd rect
			(at -0.40005 0 270)
			(size 0.4572 0.508)
			(layers "F.Cu" "F.Mask" "F.Paste")
			(net "UART_T2_NODE2_RXD_R")
		)
	)
	(footprint ""
		(layer "F.Cu")
		(at 18.746724 -144.480534)
		(property "Reference" "C415"
			(at -5.513324 0.022606 0)
			(unlocked yes)
			(layer "F.SilkS")
			(effects
				(font
					(size 0.7874 0.5842)
					(thickness 0.1524)
				)
				(justify left)
			)
		)
		(property "Value" ""
			(at 0 0 0)
			(layer "F.Fab")
			(effects
				(font
					(size 1.27 1.27)
				)
			)
		)
		(duplicate_pad_numbers_are_jumpers no)
		(fp_line
			(start -1.905 -0.8636)
			(end 1.905 -0.8636)
			(stroke
				(width 0.1524)
				(type default)
			)
			(layer "F.SilkS")
		)
		(fp_line
			(start -1.905 0.8636)
			(end -1.905 -0.8636)
			(stroke
				(width 0.1524)
				(type default)
			)
			(layer "F.SilkS")
		)
		(fp_line
			(start 0 0.8382)
			(end 0 -0.8382)
			(stroke
				(width 0.1524)
				(type default)
			)
			(layer "F.SilkS")
		)
		(fp_line
			(start 1.905 -0.8636)
			(end 1.905 0.8636)
			(stroke
				(width 0.1524)
				(type default)
			)
			(layer "F.SilkS")
		)
		(fp_line
			(start 1.905 0.8636)
			(end -1.905 0.8636)
			(stroke
				(width 0.1524)
				(type default)
			)
			(layer "F.SilkS")
		)
		(fp_rect
			(start -1.524 0.7366)
			(end 1.524 -0.7366)
			(stroke
				(width 0)
				(type default)
			)
			(fill no)
			(layer "F.CrtYd")
		)
		(pad "1" smd rect
			(at 0.94996 0)
			(size 1.1176 1.3716)
			(layers "F.Cu" "F.Mask" "F.Paste")
			(net "P3V3_NODE1")
		)
		(pad "2" smd rect
			(at -0.94996 0)
			(size 1.1176 1.3716)
			(layers "F.Cu" "F.Mask" "F.Paste")
			(net "GND")
		)
	)
	(footprint ""
		(layer "F.Cu")
		(at 153.90876 -185.205624 -90)
		(property "Reference" "R900"
			(at -4.768088 -0.259588 90)
			(unlocked yes)
			(layer "F.SilkS")
			(effects
				(font
					(size 0.7874 0.5842)
					(thickness 0.1524)
				)
				(justify left)
			)
		)
		(property "Value" ""
			(at 0 0 270)
			(layer "F.Fab")
			(effects
				(font
					(size 1.27 1.27)
				)
			)
		)
		(duplicate_pad_numbers_are_jumpers no)
		(fp_line
			(start -0.7874 0.4064)
			(end -0.7874 -0.4064)
			(stroke
				(width 0.1524)
				(type default)
			)
			(layer "F.SilkS")
		)
		(fp_line
			(start 0.7874 0.4064)
			(end -0.7874 0.4064)
			(stroke
				(width 0.1524)
				(type default)
			)
			(layer "F.SilkS")
		)
		(fp_line
			(start -0.7874 -0.4064)
			(end 0.7874 -0.4064)
			(stroke
				(width 0.1524)
				(type default)
			)
			(layer "F.SilkS")
		)
		(fp_line
			(start 0.7874 -0.4064)
			(end 0.7874 0.4064)
			(stroke
				(width 0.1524)
				(type default)
			)
			(layer "F.SilkS")
		)
		(fp_poly
			(pts
				(xy -0.508 0.2794) (xy -0.508 0.2286) (xy -0.635 0.2286) (xy -0.635 -0.254) (xy -0.5334 -0.254)
				(xy -0.5334 -0.2794) (xy 0.5334 -0.2794) (xy 0.5334 -0.254) (xy 0.635 -0.254) (xy 0.635 0.254) (xy 0.5334 0.254)
				(xy 0.5334 0.2794)
			)
			(stroke
				(width 0)
				(type default)
			)
			(fill no)
			(layer "F.CrtYd")
		)
		(pad "1" smd rect
			(at 0.40005 0 270)
			(size 0.4572 0.508)
			(layers "F.Cu" "F.Mask" "F.Paste")
			(net "T12_NODE2_EN")
		)
		(pad "2" smd rect
			(at -0.40005 0 270)
			(size 0.4572 0.508)
			(layers "F.Cu" "F.Mask" "F.Paste")
			(net "T12_NODE2_EN_R")
		)
	)
	(footprint ""
		(layer "F.Cu")
		(at 117.68836 -170.346624 -90)
		(property "Reference" "U60"
			(at 52.482496 -32.0294 0)
			(unlocked yes)
			(layer "F.SilkS")
			(effects
				(font
					(size 0.7874 0.5842)
					(thickness 0.1524)
				)
				(justify left)
			)
		)
		(property "Value" ""
			(at 0 0 270)
			(layer "F.Fab")
			(effects
				(font
					(size 1.27 1.27)
				)
			)
		)
		(duplicate_pad_numbers_are_jumpers no)
		(fp_line
			(start -2.5654 2.0066)
			(end -2.5654 0.5842)
			(stroke
				(width 0.1524)
				(type default)
			)
			(layer "F.SilkS")
		)
		(fp_line
			(start 2.5654 2.0066)
			(end -2.5654 2.0066)
			(stroke
				(width 0.1524)
				(type default)
			)
			(layer "F.SilkS")
		)
		(fp_line
			(start -2.5654 0.5842)
			(end -1.9812 0)
			(stroke
				(width 0.1524)
				(type default)
			)
			(layer "F.SilkS")
		)
		(fp_line
			(start -1.9812 0)
			(end -2.5654 -0.5842)
			(stroke
				(width 0.1524)
				(type default)
			)
			(layer "F.SilkS")
		)
		(fp_line
			(start -2.5654 -0.5842)
			(end -2.5654 -2.0066)
			(stroke
				(width 0.1524)
				(type default)
			)
			(layer "F.SilkS")
		)
		(fp_line
			(start -2.5654 -2.0066)
			(end 2.5654 -2.0066)
			(stroke
				(width 0.1524)
				(type default)
			)
			(layer "F.SilkS")
		)
		(fp_line
			(start 2.5654 -2.0066)
			(end 2.5654 2.0066)
			(stroke
				(width 0.1524)
				(type default)
			)
			(layer "F.SilkS")
		)
		(fp_circle
			(center -2.032 1.524)
			(end -2.032 1.27)
			(stroke
				(width 0.1524)
				(type default)
			)
			(fill no)
			(layer "F.SilkS")
		)
		(fp_rect
			(start -2.5654 3.6703)
			(end 2.5654 -3.6703)
			(stroke
				(width 0)
				(type default)
			)
			(fill no)
			(layer "F.CrtYd")
		)
		(pad "1" smd rect
			(at -2.275078 2.921 270)
			(size 0.3556 1.4986)
			(layers "F.Cu" "F.Mask" "F.Paste")
			(net "I2C_COM3_SCL")
		)
		(pad "2" smd rect
			(at -1.625092 2.921 270)
			(size 0.3556 1.4986)
			(layers "F.Cu" "F.Mask" "F.Paste")
			(net "I2C_COM3_SDA")
		)
		(pad "3" smd rect
			(at -0.975106 2.921 270)
			(size 0.3556 1.4986)
			(layers "F.Cu" "F.Mask" "F.Paste")
			(net "I2C_PSU1_SCL_MOS")
		)
		(pad "4" smd rect
			(at -0.32512 2.921 270)
			(size 0.3556 1.4986)
			(layers "F.Cu" "F.Mask" "F.Paste")
			(net "I2C_PSU1_SDA_MOS")
		)
		(pad "5" smd rect
			(at 0.32512 2.921 270)
			(size 0.3556 1.4986)
			(layers "F.Cu" "F.Mask" "F.Paste")
			(net "PSU1_HUB_EN")
		)
		(pad "6" smd rect
			(at 0.975106 2.921 270)
			(size 0.3556 1.4986)
			(layers "F.Cu" "F.Mask" "F.Paste")
			(net "I2C_PSU2_SCL_MOS")
		)
		(pad "7" smd rect
			(at 1.625092 2.921 270)
			(size 0.3556 1.4986)
			(layers "F.Cu" "F.Mask" "F.Paste")
			(net "I2C_PSU2_SDA_MOS")
		)
		(pad "8" smd rect
			(at 2.275078 2.921 270)
			(size 0.3556 1.4986)
			(layers "F.Cu" "F.Mask" "F.Paste")
			(net "GND")
		)
		(pad "9" smd rect
			(at 2.275078 -2.921 270)
			(size 0.3556 1.4986)
			(layers "F.Cu" "F.Mask" "F.Paste")
			(net "PSU2_HUB_EN")
		)
		(pad "10" smd rect
			(at 1.625092 -2.921 270)
			(size 0.3556 1.4986)
			(layers "F.Cu" "F.Mask" "F.Paste")
			(net "I2C_PSU3_SCL_MOS")
		)
		(pad "11" smd rect
			(at 0.975106 -2.921 270)
			(size 0.3556 1.4986)
			(layers "F.Cu" "F.Mask" "F.Paste")
			(net "I2C_PSU3_SDA_MOS")
		)
		(pad "12" smd rect
			(at 0.32512 -2.921 270)
			(size 0.3556 1.4986)
			(layers "F.Cu" "F.Mask" "F.Paste")
			(net "PSU3_HUB_EN")
		)
		(pad "13" smd rect
			(at -0.32512 -2.921 270)
			(size 0.3556 1.4986)
			(layers "F.Cu" "F.Mask" "F.Paste")
			(net "PU_I2C_SCL4")
		)
		(pad "14" smd rect
			(at -0.975106 -2.921 270)
			(size 0.3556 1.4986)
			(layers "F.Cu" "F.Mask" "F.Paste")
			(net "PU_I2C_SDA4")
		)
		(pad "15" smd rect
			(at -1.625092 -2.921 270)
			(size 0.3556 1.4986)
			(layers "F.Cu" "F.Mask" "F.Paste")
			(net "N21699069")
		)
		(pad "16" smd rect
			(at -2.275078 -2.921 270)
			(size 0.3556 1.4986)
			(layers "F.Cu" "F.Mask" "F.Paste")
			(net "P3V3_NODE1")
		)
	)
	(footprint ""
		(layer "F.Cu")
		(at 79.10576 -185.205624 -90)
		(property "Reference" "R904"
			(at -4.198112 1.795272 90)
			(unlocked yes)
			(layer "F.SilkS")
			(effects
				(font
					(size 0.7874 0.5842)
					(thickness 0.1524)
				)
				(justify left)
			)
		)
		(property "Value" ""
			(at 0 0 270)
			(layer "F.Fab")
			(effects
				(font
					(size 1.27 1.27)
				)
			)
		)
		(duplicate_pad_numbers_are_jumpers no)
		(fp_line
			(start -0.7874 0.4064)
			(end -0.7874 -0.4064)
			(stroke
				(width 0.1524)
				(type default)
			)
			(layer "F.SilkS")
		)
		(fp_line
			(start 0.7874 0.4064)
			(end -0.7874 0.4064)
			(stroke
				(width 0.1524)
				(type default)
			)
			(layer "F.SilkS")
		)
		(fp_line
			(start -0.7874 -0.4064)
			(end 0.7874 -0.4064)
			(stroke
				(width 0.1524)
				(type default)
			)
			(layer "F.SilkS")
		)
		(fp_line
			(start 0.7874 -0.4064)
			(end 0.7874 0.4064)
			(stroke
				(width 0.1524)
				(type default)
			)
			(layer "F.SilkS")
		)
		(fp_poly
			(pts
				(xy -0.508 0.2794) (xy -0.508 0.2286) (xy -0.635 0.2286) (xy -0.635 -0.254) (xy -0.5334 -0.254)
				(xy -0.5334 -0.2794) (xy 0.5334 -0.2794) (xy 0.5334 -0.254) (xy 0.635 -0.254) (xy 0.635 0.254) (xy 0.5334 0.254)
				(xy 0.5334 0.2794)
			)
			(stroke
				(width 0)
				(type default)
			)
			(fill no)
			(layer "F.CrtYd")
		)
		(pad "1" smd rect
			(at 0.40005 0 270)
			(size 0.4572 0.508)
			(layers "F.Cu" "F.Mask" "F.Paste")
			(net "T4_NODE4_EN")
		)
		(pad "2" smd rect
			(at -0.40005 0 270)
			(size 0.4572 0.508)
			(layers "F.Cu" "F.Mask" "F.Paste")
			(net "T4_NODE4_EN_R")
		)
	)
	(footprint ""
		(layer "F.Cu")
		(at 138.79576 -185.205624 -90)
		(property "Reference" "R879"
			(at -4.768088 0.474472 90)
			(unlocked yes)
			(layer "F.SilkS")
			(effects
				(font
					(size 0.7874 0.5842)
					(thickness 0.1524)
				)
				(justify left)
			)
		)
		(property "Value" ""
			(at 0 0 270)
			(layer "F.Fab")
			(effects
				(font
					(size 1.27 1.27)
				)
			)
		)
		(duplicate_pad_numbers_are_jumpers no)
		(fp_line
			(start -0.7874 0.4064)
			(end -0.7874 -0.4064)
			(stroke
				(width 0.1524)
				(type default)
			)
			(layer "F.SilkS")
		)
		(fp_line
			(start 0.7874 0.4064)
			(end -0.7874 0.4064)
			(stroke
				(width 0.1524)
				(type default)
			)
			(layer "F.SilkS")
		)
		(fp_line
			(start -0.7874 -0.4064)
			(end 0.7874 -0.4064)
			(stroke
				(width 0.1524)
				(type default)
			)
			(layer "F.SilkS")
		)
		(fp_line
			(start 0.7874 -0.4064)
			(end 0.7874 0.4064)
			(stroke
				(width 0.1524)
				(type default)
			)
			(layer "F.SilkS")
		)
		(fp_poly
			(pts
				(xy -0.508 0.2794) (xy -0.508 0.2286) (xy -0.635 0.2286) (xy -0.635 -0.254) (xy -0.5334 -0.254)
				(xy -0.5334 -0.2794) (xy 0.5334 -0.2794) (xy 0.5334 -0.254) (xy 0.635 -0.254) (xy 0.635 0.254) (xy 0.5334 0.254)
				(xy 0.5334 0.2794)
			)
			(stroke
				(width 0)
				(type default)
			)
			(fill no)
			(layer "F.CrtYd")
		)
		(pad "1" smd rect
			(at 0.40005 0 270)
			(size 0.4572 0.508)
			(layers "F.Cu" "F.Mask" "F.Paste")
			(net "T10_NODE3_EN")
		)
		(pad "2" smd rect
			(at -0.40005 0 270)
			(size 0.4572 0.508)
			(layers "F.Cu" "F.Mask" "F.Paste")
			(net "T10_NODE3_EN_R")
		)
	)
	(footprint ""
		(layer "F.Cu")
		(at 156.19476 -185.205624 -90)
		(property "Reference" "R825"
			(at -4.768088 -0.297942 90)
			(unlocked yes)
			(layer "F.SilkS")
			(effects
				(font
					(size 0.7874 0.5842)
					(thickness 0.1524)
				)
				(justify left)
			)
		)
		(property "Value" ""
			(at 0 0 270)
			(layer "F.Fab")
			(effects
				(font
					(size 1.27 1.27)
				)
			)
		)
		(duplicate_pad_numbers_are_jumpers no)
		(fp_line
			(start -0.7874 0.4064)
			(end -0.7874 -0.4064)
			(stroke
				(width 0.1524)
				(type default)
			)
			(layer "F.SilkS")
		)
		(fp_line
			(start 0.7874 0.4064)
			(end -0.7874 0.4064)
			(stroke
				(width 0.1524)
				(type default)
			)
			(layer "F.SilkS")
		)
		(fp_line
			(start -0.7874 -0.4064)
			(end 0.7874 -0.4064)
			(stroke
				(width 0.1524)
				(type default)
			)
			(layer "F.SilkS")
		)
		(fp_line
			(start 0.7874 -0.4064)
			(end 0.7874 0.4064)
			(stroke
				(width 0.1524)
				(type default)
			)
			(layer "F.SilkS")
		)
		(fp_poly
			(pts
				(xy -0.508 0.2794) (xy -0.508 0.2286) (xy -0.635 0.2286) (xy -0.635 -0.254) (xy -0.5334 -0.254)
				(xy -0.5334 -0.2794) (xy 0.5334 -0.2794) (xy 0.5334 -0.254) (xy 0.635 -0.254) (xy 0.635 0.254) (xy 0.5334 0.254)
				(xy 0.5334 0.2794)
			)
			(stroke
				(width 0)
				(type default)
			)
			(fill no)
			(layer "F.CrtYd")
		)
		(pad "1" smd rect
			(at 0.40005 0 270)
			(size 0.4572 0.508)
			(layers "F.Cu" "F.Mask" "F.Paste")
			(net "FAN3_TACH")
		)
		(pad "2" smd rect
			(at -0.40005 0 270)
			(size 0.4572 0.508)
			(layers "F.Cu" "F.Mask" "F.Paste")
			(net "FAN3_TACH_R")
		)
	)
)
